# BASEBOARD_FAB2 (Tioga Pass) — schematic netlist excerpt (pin names and nets, part order shuffled) for the footprints in the layout excerpt that follows; sources: Cadence DE-HDL packaged netlist, KiCad conversion of Wiwynn_Tioga_Pass_MB.brd

S9W1  SW-SLIDE75-GP  pkg DISCRET-G6  page 255
  \1\  = NC
  \2\  = BMC_JTAG_SEL
  \3\  = GND
  \4\  = GND
  \5\  = GND
  \6\  = GND
  \7\  = GND
  NP1  = NC
  NP2  = NC

(kicad_pcb
	(version 20260206)
	(generator "pcbnew")
	(generator_version "10.0")
	(general
		(thickness 1.6)
		(legacy_teardrops no)
	)
	(paper "A4")
	(title_block
		(title "Wiwynn_Tioga_Pass_MB.brd")
		(comment 1 "Tioga Pass / footprints 126-126 of 4770")
	)
	(layers
		(0 "F.Cu" signal "TOP")
		(4 "In1.Cu" signal "L2GND")
		(6 "In2.Cu" signal "L3")
		(8 "In3.Cu" signal "L4GND")
		(10 "In4.Cu" signal "L5")
		(12 "In5.Cu" signal "L6GND")
		(14 "In6.Cu" signal "L7VCC")
		(16 "In7.Cu" signal "L8VCC")
		(18 "In8.Cu" signal "L9GND")
		(20 "In9.Cu" signal "L10")
		(22 "In10.Cu" signal "L11GND")
		(24 "In11.Cu" signal "L12")
		(26 "In12.Cu" signal "L13GND")
		(2 "B.Cu" signal "BOTTOM")
		(9 "F.Adhes" user "F.Adhesive")
		(11 "B.Adhes" user "B.Adhesive")
		(13 "F.Paste" user "Package Geometry/Pastemask Top")
		(15 "B.Paste" user "Package Geometry/Pastemask Bottom")
		(5 "F.SilkS" user "Ref Des/Silkscreen Top")
		(7 "B.SilkS" user "Ref Des/Silkscreen Bottom")
		(1 "F.Mask" user "Board Geometry/Soldermask Top")
		(3 "B.Mask" user "Board Geometry/Soldermask Bottom")
		(17 "Dwgs.User" user "User.Drawings")
		(19 "Cmts.User" user "User.Comments")
		(21 "Eco1.User" user "User.Eco1")
		(23 "Eco2.User" user "User.Eco2")
		(25 "Edge.Cuts" user "Board Geometry/Outline")
		(27 "Margin" user)
		(31 "F.CrtYd" user "Package Geometry/Place Bound Top")
		(29 "B.CrtYd" user "Package Geometry/Place Bound Bottom")
		(35 "F.Fab" user "Ref Des/Assembly Top")
		(33 "B.Fab" user "Ref Des/Assembly Bottom")
	)
	(footprint ""
		(layer "F.Cu")
		(at 500.199914 -124.960126 90)
		(property "Reference" "S9W1"
			(at 0 0 90)
			(layer "F.SilkS")
			(hide yes)
			(effects
				(font
					(size 1.27 1.27)
				)
			)
		)
		(property "Value" "*"
			(at -6.092952 -8.046466 90)
			(unlocked yes)
			(layer "F.Fab")
			(hide yes)
			(effects
				(font
					(size 0.889 0.889)
					(thickness 0.1524)
				)
			)
		)
		(property "Device Type" "SW-SLIDE75-GP_DISCRET-G6-SW-SLA"
			(at -6.092952 -6.522466 90)
			(unlocked yes)
			(layer "F.Fab")
			(hide yes)
			(effects
				(font
					(size 0.889 0.889)
					(thickness 0.1524)
				)
			)
		)
		(duplicate_pad_numbers_are_jumpers no)
		(fp_line
			(start -2.0701 -2.8956)
			(end -2.4511 -2.8956)
			(stroke
				(width 0.3302)
				(type default)
			)
			(layer "F.SilkS")
		)
		(fp_line
			(start 4.4069 -2.7686)
			(end 4.4069 1.7272)
			(stroke
				(width 0.1524)
				(type default)
			)
			(layer "F.SilkS")
		)
		(fp_line
			(start -4.4069 -2.7686)
			(end 4.4069 -2.7686)
			(stroke
				(width 0.1524)
				(type default)
			)
			(layer "F.SilkS")
		)
		(fp_line
			(start 4.4069 1.7272)
			(end 1.651 1.7272)
			(stroke
				(width 0.1524)
				(type default)
			)
			(layer "F.SilkS")
		)
		(fp_line
			(start 1.651 1.7272)
			(end 1.651 3.048)
			(stroke
				(width 0.1524)
				(type default)
			)
			(layer "F.SilkS")
		)
		(fp_line
			(start -1.651 1.7272)
			(end -4.4069 1.7272)
			(stroke
				(width 0.1524)
				(type default)
			)
			(layer "F.SilkS")
		)
		(fp_line
			(start -4.4069 1.7272)
			(end -4.4069 -2.7686)
			(stroke
				(width 0.1524)
				(type default)
			)
			(layer "F.SilkS")
		)
		(fp_line
			(start 1.651 3.048)
			(end -1.651 3.048)
			(stroke
				(width 0.1524)
				(type default)
			)
			(layer "F.SilkS")
		)
		(fp_line
			(start -1.651 3.048)
			(end -1.651 1.7272)
			(stroke
				(width 0.1524)
				(type default)
			)
			(layer "F.SilkS")
		)
		(fp_poly
			(pts
				(xy -2.2606 -2.8194) (xy -2.6416 -3.2004) (xy -1.8796 -3.2004)
			)
			(stroke
				(width 0)
				(type default)
			)
			(fill yes)
			(layer "F.SilkS")
		)
		(fp_poly
			(pts
				(xy -1.397 2.794) (xy -1.397 1.2954) (xy -3.8481 1.2954) (xy -3.8481 -2.2098) (xy 3.8481 -2.2098)
				(xy 3.8481 1.2954) (xy 1.397 1.2954) (xy 1.397 2.794)
			)
			(stroke
				(width 0)
				(type default)
			)
			(fill no)
			(layer "F.CrtYd")
		)
		(fp_poly
			(pts
				(xy -0.3302 3.302) (xy -0.3302 2.794) (xy -1.397 2.794) (xy -1.397 1.2954) (xy -3.8481 1.2954) (xy -3.8481 -2.2098)
				(xy 3.8481 -2.2098) (xy 3.8481 1.2954) (xy 1.397 1.2954) (xy 1.397 2.794) (xy -0.3175 2.794) (xy -0.3175 3.302)
				(xy 1.905 3.302) (xy 1.905 1.9812) (xy 4.6609 1.9812) (xy 4.6609 -3.0226) (xy -4.6609 -3.0226) (xy -4.6609 1.9812)
				(xy -1.905 1.9812) (xy -1.905 3.302)
			)
			(stroke
				(width 0)
				(type default)
			)
			(fill no)
			(layer "F.CrtYd")
		)
		(fp_poly
			(pts
				(xy -1.905 3.302) (xy -1.905 1.9812) (xy -4.6609 1.9812) (xy -4.6609 -3.0226) (xy 4.6609 -3.0226)
				(xy 4.6609 1.9812) (xy 1.905 1.9812) (xy 1.905 3.302)
			)
			(stroke
				(width 0)
				(type default)
			)
			(fill no)
			(layer "F.Fab")
		)
		(pad "" np_thru_hole circle
			(at -1.49987 0 90)
			(size 0.254 0.254)
			(drill 0.9144)
			(layers "*.Cu" "*.Mask")
			(clearance 0.6858)
			(thermal_gap 0.6858)
		)
		(pad "" np_thru_hole circle
			(at 1.49987 0 90)
			(size 0.254 0.254)
			(drill 0.9144)
			(layers "*.Cu" "*.Mask")
			(clearance 0.6858)
			(thermal_gap 0.6858)
		)
		(pad "1" smd rect
			(at -2.25044 -1.75006 90)
			(size 0.7112 1.4986)
			(layers "F.Cu" "F.Mask" "F.Paste")
			(net "Net_6516")
		)
		(pad "2" smd rect
			(at 0.75057 -1.75006 90)
			(size 0.7112 1.4986)
			(layers "F.Cu" "F.Mask" "F.Paste")
			(net "BMC_JTAG_SEL")
		)
		(pad "3" smd rect
			(at 2.25044 -1.75006 90)
			(size 0.7112 1.4986)
			(layers "F.Cu" "F.Mask" "F.Paste")
			(net "GND")
		)
		(pad "4" smd rect
			(at -3.64998 -1.056386 90)
			(size 0.9906 0.8128)
			(layers "F.Cu" "F.Mask" "F.Paste")
			(net "GND")
		)
		(pad "5" smd rect
			(at -3.64998 1.056386 90)
			(size 0.9906 0.8128)
			(layers "F.Cu" "F.Mask" "F.Paste")
			(net "GND")
		)
		(pad "6" smd rect
			(at 3.64998 -1.056386 90)
			(size 0.9906 0.8128)
			(layers "F.Cu" "F.Mask" "F.Paste")
			(net "GND")
		)
		(pad "7" smd rect
			(at 3.64998 1.056386 90)
			(size 0.9906 0.8128)
			(layers "F.Cu" "F.Mask" "F.Paste")
			(net "GND")
		)
		(zone
			(layers "F.Cu" "B.Cu" "In1.Cu" "In2.Cu" "In3.Cu" "In4.Cu" "In5.Cu" "In6.Cu"
				"In7.Cu" "In8.Cu" "In9.Cu" "In10.Cu" "In11.Cu" "In12.Cu"
			)
			(hatch none 0.5)
			(connect_pads
				(clearance 0)
			)
			(min_thickness 0.25)
			(keepout
				(tracks not_allowed)
				(vias allowed)
				(pads allowed)
				(copperpour not_allowed)
				(footprints allowed)
			)
			(placement
				(enabled no)
				(sheetname "")
			)
			(fill
				(thermal_gap 0.5)
				(thermal_bridge_width 0.5)
				(island_removal_mode 0)
			)
			(polygon
				(pts
					(arc
						(start 500.961914 -126.459996)
						(mid 499.437914 -126.459996)
						(end 500.961914 -126.459996)
					)
				)
			)
		)
		(zone
			(layers "F.Cu" "B.Cu" "In1.Cu" "In2.Cu" "In3.Cu" "In4.Cu" "In5.Cu" "In6.Cu"
				"In7.Cu" "In8.Cu" "In9.Cu" "In10.Cu" "In11.Cu" "In12.Cu"
			)
			(hatch none 0.5)
			(connect_pads
				(clearance 0)
			)
			(min_thickness 0.25)
			(keepout
				(tracks not_allowed)
				(vias allowed)
				(pads allowed)
				(copperpour not_allowed)
				(footprints allowed)
			)
			(placement
				(enabled no)
				(sheetname "")
			)
			(fill
				(thermal_gap 0.5)
				(thermal_bridge_width 0.5)
				(island_removal_mode 0)
			)
			(polygon
				(pts
					(arc
						(start 500.961914 -123.460256)
						(mid 499.437914 -123.460256)
						(end 500.961914 -123.460256)
					)
				)
			)
		)
	)
)
